# T6G (Grand Teton) — schematic netlist excerpt (pin names and nets, part order shuffled) for the footprints in the layout excerpt that follows; sources: Cadence DE-HDL packaged netlist, KiCad conversion of 04192023_DAF0TMB3IC0_F0TG_MB_C_brd_V02_OCP.brd

J23  SCONN288_DDR506112002KQ  IO  pkg DDR288S_1-1VXC  page 91
  VIN_BULK0  = P12V_MEM_CPU0
  RFU0  = NC
  VIN_MGMT  = P3V3_AUX
  HSCL  = I3C_SPD_DDRF_CPU0_SCL
  HSDA  = I3C_SPD_DDRF_CPU0_SDA
  VSS0  = GND
  DQ0_A  = M_F_CPU0_SA_DQ<0>
  VSS1  = GND
  DQ1_A  = M_F_CPU0_SA_DQ<1>
  VSS2  = GND
  DQS0_A_T  = M_F_CPU0_SA_DQS_DP<0>
  DQS0_A_C  = M_F_CPU0_SA_DQS_DN<0>
  VSS3  = GND
  DQ4_A  = M_F_CPU0_SA_DQ<4>
  VSS4  = GND
  DQ5_A  = M_F_CPU0_SA_DQ<5>
  VSS5  = GND
  DQ8_A  = M_F_CPU0_SA_DQ<8>
  VSS6  = GND
  DQ9_A  = M_F_CPU0_SA_DQ<9>
  VSS7  = GND
  DQS1_A_T  = M_F_CPU0_SA_DQS_DP<1>
  DQS1_A_C  = M_F_CPU0_SA_DQS_DN<1>
  VSS8  = GND
  DQ12_A  = M_F_CPU0_SA_DQ<12>
  VSS9  = GND
  DQ13_A  = M_F_CPU0_SA_DQ<13>
  VSS10  = GND
  DQ16_A  = M_F_CPU0_SA_DQ<16>
  VSS11  = GND
  DQ17_A  = M_F_CPU0_SA_DQ<17>
  VSS12  = GND
  DQS2_A_T  = M_F_CPU0_SA_DQS_DP<2>
  DQS2_A_C  = M_F_CPU0_SA_DQS_DN<2>
  VSS13  = GND
  DQ20_A  = M_F_CPU0_SA_DQ<20>
  VSS14  = GND
  DQ21_A  = M_F_CPU0_SA_DQ<21>
  VSS15  = GND
  DQ24_A  = M_F_CPU0_SA_DQ<24>
  VSS16  = GND
  DQ25_A  = M_F_CPU0_SA_DQ<25>
  VSS17  = GND
  DQS3_A_T  = M_F_CPU0_SA_DQS_DP<3>
  DQS3_A_C  = M_F_CPU0_SA_DQS_DN<3>
  VSS18  = GND
  DQ28_A  = M_F_CPU0_SA_DQ<28>
  VSS19  = GND
  DQ29_A  = M_F_CPU0_SA_DQ<29>
  VSS20  = GND
  CB0_A  = M_F_CPU0_SA_CB<0>
  VSS21  = GND
  CB1_A  = M_F_CPU0_SA_CB<1>
  VSS22  = GND
  DQS4_A_T  = M_F_CPU0_SA_DQS_DP<4>
  DQS4_A_C  = M_F_CPU0_SA_DQS_DN<4>
  VSS23  = GND
  CB4_A  = M_F_CPU0_SA_CB<4>
  VSS24  = GND
  CB5_A  = M_F_CPU0_SA_CB<5>
  VSS25  = GND
  ALERT_N  = M_F_CPU0_ALERT_N
  VSS26  = GND
  CS0_A_N  = M_F_CPU0_SA_CS_N<0>
  VSS27  = GND
  CA0_A  = M_F_CPU0_SA_CA<0>
  VSS28  = GND
  CA2_A  = M_F_CPU0_SA_CA<2>
  VSS29  = GND
  CA4_A  = M_F_CPU0_SA_CA<4>
  VSS30  = GND
  CA6_A  = M_F_CPU0_SA_CA<6>
  VSS31  = GND
  PAR_A  = M_F_CPU0_SA_PAR
  VSS32  = GND
  CA0_B  = M_F_CPU0_SB_CA<0>
  VSS33  = GND
  CA2_B  = M_F_CPU0_SB_CA<2>
  VSS34  = GND
  CA4_B  = M_F_CPU0_SB_CA<4>
  VSS35  = GND
  CA6_B  = M_F_CPU0_SB_CA<6>
  VSS36  = GND
  CS0_B_N  = M_F_CPU0_SB_CS_N<0>
  VSS37  = GND
  \lbd||rsp_a_n\  = M_F_CPU0_SA_RSP<0>
  \lbs||rsp_b_n\  = M_F_CPU0_SB_RSP<0>
  VSS38  = GND
  CB4_B  = M_F_CPU0_SB_CB<4>
  VSS39  = GND
  CB5_B  = M_F_CPU0_SB_CB<5>
  VSS40  = GND
  \dqs9_b_t||tdqs9_b_t||dbi4_b_n\  = M_F_CPU0_SB_DQS_DP<9>
  \dqs9_b_c||tdqs9_b_c\  = M_F_CPU0_SB_DQS_DN<9>
  VSS41  = GND
  CB0_B  = M_F_CPU0_SB_CB<0>
  VSS42  = GND
  CB1_B  = M_F_CPU0_SB_CB<1>
  VSS43  = GND
  DQ0_B  = M_F_CPU0_SB_DQ<0>
  VSS44  = GND
  DQ1_B  = M_F_CPU0_SB_DQ<1>
  VSS45  = GND
  DQS0_B_T  = M_F_CPU0_SB_DQS_DP<0>
  DQS0_B_C  = M_F_CPU0_SB_DQS_DN<0>
  VSS46  = GND
  DQ4_B  = M_F_CPU0_SB_DQ<4>
  VSS47  = GND
  DQ5_B  = M_F_CPU0_SB_DQ<5>
  VSS48  = GND
  DQ8_B  = M_F_CPU0_SB_DQ<8>
  VSS49  = GND
  DQ9_B  = M_F_CPU0_SB_DQ<9>
  VSS50  = GND
  DQS1_B_T  = M_F_CPU0_SB_DQS_DP<1>
  DQS1_B_C  = M_F_CPU0_SB_DQS_DN<1>
  VSS51  = GND
  DQ12_B  = M_F_CPU0_SB_DQ<12>
  VSS52  = GND
  DQ13_B  = M_F_CPU0_SB_DQ<13>
  VSS53  = GND
  DQ16_B  = M_F_CPU0_SB_DQ<16>
  VSS54  = GND
  DQ17_B  = M_F_CPU0_SB_DQ<17>
  VSS55  = GND
  DQS2_B_T  = M_F_CPU0_SB_DQS_DP<2>
  DQS2_B_C  = M_F_CPU0_SB_DQS_DN<2>
  VSS56  = GND
  DQ20_B  = M_F_CPU0_SB_DQ<20>
  VSS57  = GND
  DQ21_B  = M_F_CPU0_SB_DQ<21>
  VSS58  = GND
  DQ24_B  = M_F_CPU0_SB_DQ<24>
  VSS59  = GND
  DQ25_B  = M_F_CPU0_SB_DQ<25>
  VSS60  = GND
  DQS3_B_T  = M_F_CPU0_SB_DQS_DP<3>
  DQS3_B_C  = M_F_CPU0_SB_DQS_DN<3>
  VSS61  = GND
  DQ28_B  = M_F_CPU0_SB_DQ<28>
  VSS62  = GND
  DQ29_B  = M_F_CPU0_SB_DQ<29>
  VSS63  = GND
  RFU1  = NC
  VIN_BULK1  = P12V_MEM_CPU0
  VIN_BULK2  = P12V_MEM_CPU0
  \pwr_good||fail_n\  = PWRGD_CHF_CPU0_DIMM
  HAS  = PD_CHF_CPU0_DIMM_SAA
  RFU2  = NC
  RFU3  = NC
  VSS64  = GND
  DQ2_A  = M_F_CPU0_SA_DQ<2>
  VSS65  = GND
  DQ3_A  = M_F_CPU0_SA_DQ<3>
  VSS66  = GND
  \dqs5_a_c||tdqs5_a_c||dqs5_a_t||tdqs5_a_t\  = M_F_CPU0_SA_DQS_DN<5>
  \dqs5_a_t||tdqs5_a_t\  = M_F_CPU0_SA_DQS_DP<5>
  VSS67  = GND
  DQ6_A  = M_F_CPU0_SA_DQ<6>
  VSS68  = GND
  DQ7_A  = M_F_CPU0_SA_DQ<7>
  VSS69  = GND
  DQ10_A  = M_F_CPU0_SA_DQ<10>
  VSS70  = GND
  DQ11_A  = M_F_CPU0_SA_DQ<11>
  VSS71  = GND
  \dqs6_a_c||tdqs6_a_c||dqs6_a_t||tdqs6_a_t\  = M_F_CPU0_SA_DQS_DN<6>
  \dqs6_a_t||tdqs6_a_t\  = M_F_CPU0_SA_DQS_DP<6>
  VSS72  = GND
  DQ14_A  = M_F_CPU0_SA_DQ<14>
  VSS73  = GND
  DQ15_A  = M_F_CPU0_SA_DQ<15>
  VSS74  = GND
  DQ18_A  = M_F_CPU0_SA_DQ<18>
  VSS75  = GND
  DQ19_A  = M_F_CPU0_SA_DQ<19>
  VSS76  = GND
  \dqs7_a_c||tdqs7_a_c\  = M_F_CPU0_SA_DQS_DN<7>
  \dqs7_a_t||tdqs7_a_t\  = M_F_CPU0_SA_DQS_DP<7>
  VSS77  = GND
  DQ22_A  = M_F_CPU0_SA_DQ<22>
  VSS78  = GND
  DQ23_A  = M_F_CPU0_SA_DQ<23>
  VSS79  = GND
  DQ26_A  = M_F_CPU0_SA_DQ<26>
  VSS80  = GND
  DQ27_A  = M_F_CPU0_SA_DQ<27>
  VSS81  = GND
  \dqs8_a_c||tdqs8_a_c\  = M_F_CPU0_SA_DQS_DN<8>
  \dqs8_a_t||tdqs8_a_t\  = M_F_CPU0_SA_DQS_DP<8>
  VSS82  = GND
  DQ30_A  = M_F_CPU0_SA_DQ<30>
  VSS83  = GND
  DQ31_A  = M_F_CPU0_SA_DQ<31>
  VSS84  = GND
  CB2_A  = M_F_CPU0_SA_CB<2>
  VSS85  = GND
  CB3_A  = M_F_CPU0_SA_CB<3>
  VSS86  = GND
  \dqs9_a_c||tdqs9_a_c\  = M_F_CPU0_SA_DQS_DN<9>
  \dqs9_a_t||tdqs9_a_t\  = M_F_CPU0_SA_DQS_DP<9>
  VSS87  = GND
  CB6_A  = M_F_CPU0_SA_CB<6>
  VSS88  = GND
  CB7_A  = M_F_CPU0_SA_CB<7>
  VSS89  = GND
  RESET_N  = M_F_CPU0_RESET_N
  VSS90  = GND
  CS1_A_N  = M_F_CPU0_SA_CS_N<1>
  VSS91  = GND
  CA1_A  = M_F_CPU0_SA_CA<1>
  VSS92  = GND
  CA3_A  = M_F_CPU0_SA_CA<3>
  VSS93  = GND
  CA5_A  = M_F_CPU0_SA_CA<5>
  VSS94  = GND
  CK_T  = M_F_CPU0_CLK_DP<0>
  CK_C  = M_F_CPU0_CLK_DN<0>
  VSS95  = GND
  RFU4  = NC
  CA1_B  = M_F_CPU0_SB_CA<1>
  VSS96  = GND
  CA3_B  = M_F_CPU0_SB_CA<3>
  VSS97  = GND
  CA5_B  = M_F_CPU0_SB_CA<5>
  VSS98  = GND
  PAR_B  = M_F_CPU0_SB_PAR
  VSS99  = GND
  CS1_B_N  = M_F_CPU0_SB_CS_N<1>
  VSS100  = GND
  RFU5  = NC
  RFU6  = NC
  VSS101  = GND
  CB6_B  = M_F_CPU0_SB_CB<6>
  VSS102  = GND
  CB7_B  = M_F_CPU0_SB_CB<7>
  VSS103  = GND
  DQS4_B_C  = M_F_CPU0_SB_DQS_DN<4>
  DQS4_B_T  = M_F_CPU0_SB_DQS_DP<4>
  VSS104  = GND
  CB2_B  = M_F_CPU0_SB_CB<2>
  VSS105  = GND
  CB3_B  = M_F_CPU0_SB_CB<3>
  VSS106  = GND
  DQ2_B  = M_F_CPU0_SB_DQ<2>
  VSS107  = GND
  DQ3_B  = M_F_CPU0_SB_DQ<3>
  VSS108  = GND
  \dqs5_b_c||tdqs5_b_c\  = M_F_CPU0_SB_DQS_DN<5>
  \dqs5_b_t||tdqs5_b_t\  = M_F_CPU0_SB_DQS_DP<5>
  VSS109  = GND
  DQ6_B  = M_F_CPU0_SB_DQ<6>
  VSS110  = GND
  DQ7_B  = M_F_CPU0_SB_DQ<7>
  VSS111  = GND
  DQ10_B  = M_F_CPU0_SB_DQ<10>
  VSS112  = GND
  DQ11_B  = M_F_CPU0_SB_DQ<11>
  VSS113  = GND
  \dqs6_b_c||tdqs6_b_c\  = M_F_CPU0_SB_DQS_DN<6>
  \dqs6_b_t||tdqs6_b_t\  = M_F_CPU0_SB_DQS_DP<6>
  VSS114  = GND
  DQ14_B  = M_F_CPU0_SB_DQ<14>
  VSS115  = GND
  DQ15_B  = M_F_CPU0_SB_DQ<15>
  VSS116  = GND
  DQ18_B  = M_F_CPU0_SB_DQ<18>
  VSS117  = GND
  DQ19_B  = M_F_CPU0_SB_DQ<19>
  VSS118  = GND
  \dqs7_b_c||tdqs7_b_c\  = M_F_CPU0_SB_DQS_DN<7>
  \dqs7_b_t||tdqs7_b_t\  = M_F_CPU0_SB_DQS_DP<7>
  VSS119  = GND
  DQ22_B  = M_F_CPU0_SB_DQ<22>
  VSS120  = GND
  DQ23_B  = M_F_CPU0_SB_DQ<23>
  VSS121  = GND
  DQ26_B  = M_F_CPU0_SB_DQ<26>
  VSS122  = GND
  DQ27_B  = M_F_CPU0_SB_DQ<27>
  VSS123  = GND
  \dqs8_b_c||tdqs8_b_c\  = M_F_CPU0_SB_DQS_DN<8>
  \dqs8_b_t||tdqs8_b_t\  = M_F_CPU0_SB_DQS_DP<8>
  VSS124  = GND
  DQ30_B  = M_F_CPU0_SB_DQ<30>
  VSS125  = GND
  DQ31_B  = M_F_CPU0_SB_DQ<31>
  VSS126  = GND
  G1  = GND
  G2  = GND
  G3  = GND

(kicad_pcb
	(version 20260206)
	(generator "pcbnew")
	(generator_version "10.0")
	(general
		(thickness 1.6)
		(legacy_teardrops no)
	)
	(paper "A4")
	(title_block
		(title "04192023_DAF0TMB3IC0_F0TG_MB_C_brd_V02_OCP.brd")
		(comment 1 "Grand Teton / footprint 2449 of 8354 (J23), pads 139-184 of 291")
	)
	(layers
		(0 "F.Cu" signal "TOP")
		(4 "In1.Cu" signal "GND")
		(6 "In2.Cu" signal "IN1")
		(8 "In3.Cu" signal "GND1")
		(10 "In4.Cu" signal "IN2")
		(12 "In5.Cu" signal "GND2")
		(14 "In6.Cu" signal "IN3")
		(16 "In7.Cu" signal "GND3")
		(18 "In8.Cu" signal "VCC")
		(20 "In9.Cu" signal "VCC1")
		(22 "In10.Cu" signal "GND4")
		(24 "In11.Cu" signal "IN4")
		(26 "In12.Cu" signal "GND5")
		(28 "In13.Cu" signal "IN5")
		(30 "In14.Cu" signal "GND6")
		(32 "In15.Cu" signal "IN6")
		(34 "In16.Cu" signal "GND7")
		(2 "B.Cu" signal "BOTTOM")
		(9 "F.Adhes" user "F.Adhesive")
		(11 "B.Adhes" user "B.Adhesive")
		(13 "F.Paste" user "Package Geometry/Pastemask Top")
		(15 "B.Paste" user "Package Geometry/Pastemask Bottom")
		(5 "F.SilkS" user "Ref Des/Silkscreen Top")
		(7 "B.SilkS" user "Ref Des/Silkscreen Bottom")
		(1 "F.Mask" user "Board Geometry/Soldermask Top")
		(3 "B.Mask" user "Board Geometry/Soldermask Bottom")
		(17 "Dwgs.User" user "User.Drawings")
		(19 "Cmts.User" user "User.Comments")
		(21 "Eco1.User" user "User.Eco1")
		(23 "Eco2.User" user "User.Eco2")
		(25 "Edge.Cuts" user "Board Geometry/Outline")
		(27 "Margin" user)
		(31 "F.CrtYd" user "Package Geometry/Place Bound Top")
		(29 "B.CrtYd" user "Package Geometry/Place Bound Bottom")
		(35 "F.Fab" user "Ref Des/Assembly Top")
		(33 "B.Fab" user "Ref Des/Assembly Bottom")
	)
	(footprint ""
		(layer "F.Cu")
		(at 267.598144 -255.560068 180)
		(property "Reference" "J23"
			(at -2.2098 -81.984088 0)
			(unlocked yes)
			(layer "F.SilkS")
			(effects
				(font
					(size 0.7874 0.5842)
					(thickness 0.1524)
				)
			)
		)
		(property "Value" ""
			(at 0 0 180)
			(layer "F.Fab")
			(effects
				(font
					(size 1.27 1.27)
				)
			)
		)
		(duplicate_pad_numbers_are_jumpers no)
		(pad "139" smd rect
			(at -2.050034 59.075066 90)
			(size 0.519938 1.4986)
			(layers "F.Cu" "F.Mask" "F.Paste")
			(net "GND")
		)
		(pad "140" smd rect
			(at -2.050034 59.92495 90)
			(size 0.519938 1.4986)
			(layers "F.Cu" "F.Mask" "F.Paste")
			(net "M_F_CPU0_SB_DQ<28>")
		)
		(pad "141" smd rect
			(at -2.050034 60.775088 90)
			(size 0.519938 1.4986)
			(layers "F.Cu" "F.Mask" "F.Paste")
			(net "GND")
		)
		(pad "142" smd rect
			(at -2.050034 61.624972 90)
			(size 0.519938 1.4986)
			(layers "F.Cu" "F.Mask" "F.Paste")
			(net "M_F_CPU0_SB_DQ<29>")
		)
		(pad "143" smd rect
			(at -2.050034 62.47511 90)
			(size 0.519938 1.4986)
			(layers "F.Cu" "F.Mask" "F.Paste")
			(net "GND")
		)
		(pad "144" smd rect
			(at -2.050034 63.324994 90)
			(size 0.519938 1.4986)
			(layers "F.Cu" "F.Mask" "F.Paste")
			(net "Net_2320")
		)
		(pad "145" smd rect
			(at 2.050034 -63.324994 90)
			(size 0.519938 1.4986)
			(layers "F.Cu" "F.Mask" "F.Paste")
			(net "P12V_MEM_CPU0")
		)
		(pad "146" smd rect
			(at 2.050034 -62.47511 90)
			(size 0.519938 1.4986)
			(layers "F.Cu" "F.Mask" "F.Paste")
			(net "P12V_MEM_CPU0")
		)
		(pad "147" smd rect
			(at 2.050034 -61.624972 90)
			(size 0.519938 1.4986)
			(layers "F.Cu" "F.Mask" "F.Paste")
			(net "PWRGD_CHF_CPU0_DIMM")
		)
		(pad "148" smd rect
			(at 2.050034 -60.775088 90)
			(size 0.519938 1.4986)
			(layers "F.Cu" "F.Mask" "F.Paste")
			(net "PD_CHF_CPU0_DIMM_SAA")
		)
		(pad "149" smd rect
			(at 2.050034 -59.92495 90)
			(size 0.519938 1.4986)
			(layers "F.Cu" "F.Mask" "F.Paste")
			(net "Net_2321")
		)
		(pad "150" smd rect
			(at 2.050034 -59.075066 90)
			(size 0.519938 1.4986)
			(layers "F.Cu" "F.Mask" "F.Paste")
			(net "Net_2322")
		)
		(pad "151" smd rect
			(at 2.050034 -58.224928 90)
			(size 0.519938 1.4986)
			(layers "F.Cu" "F.Mask" "F.Paste")
			(net "GND")
		)
		(pad "152" smd rect
			(at 2.050034 -57.375044 90)
			(size 0.519938 1.4986)
			(layers "F.Cu" "F.Mask" "F.Paste")
			(net "M_F_CPU0_SA_DQ<2>")
		)
		(pad "153" smd rect
			(at 2.050034 -56.524906 90)
			(size 0.519938 1.4986)
			(layers "F.Cu" "F.Mask" "F.Paste")
			(net "GND")
		)
		(pad "154" smd rect
			(at 2.050034 -55.675022 90)
			(size 0.519938 1.4986)
			(layers "F.Cu" "F.Mask" "F.Paste")
			(net "M_F_CPU0_SA_DQ<3>")
		)
		(pad "155" smd rect
			(at 2.050034 -54.824884 90)
			(size 0.519938 1.4986)
			(layers "F.Cu" "F.Mask" "F.Paste")
			(net "GND")
		)
		(pad "156" smd rect
			(at 2.050034 -53.975 90)
			(size 0.519938 1.4986)
			(layers "F.Cu" "F.Mask" "F.Paste")
			(net "M_F_CPU0_SA_DQS_DN<5>")
		)
		(pad "157" smd rect
			(at 2.050034 -53.125116 90)
			(size 0.519938 1.4986)
			(layers "F.Cu" "F.Mask" "F.Paste")
			(net "M_F_CPU0_SA_DQS_DP<5>")
		)
		(pad "158" smd rect
			(at 2.050034 -52.274978 90)
			(size 0.519938 1.4986)
			(layers "F.Cu" "F.Mask" "F.Paste")
			(net "GND")
		)
		(pad "159" smd rect
			(at 2.050034 -51.425094 90)
			(size 0.519938 1.4986)
			(layers "F.Cu" "F.Mask" "F.Paste")
			(net "M_F_CPU0_SA_DQ<6>")
		)
		(pad "160" smd rect
			(at 2.050034 -50.574956 90)
			(size 0.519938 1.4986)
			(layers "F.Cu" "F.Mask" "F.Paste")
			(net "GND")
		)
		(pad "161" smd rect
			(at 2.050034 -49.725072 90)
			(size 0.519938 1.4986)
			(layers "F.Cu" "F.Mask" "F.Paste")
			(net "M_F_CPU0_SA_DQ<7>")
		)
		(pad "162" smd rect
			(at 2.050034 -48.874934 90)
			(size 0.519938 1.4986)
			(layers "F.Cu" "F.Mask" "F.Paste")
			(net "GND")
		)
		(pad "163" smd rect
			(at 2.050034 -48.02505 90)
			(size 0.519938 1.4986)
			(layers "F.Cu" "F.Mask" "F.Paste")
			(net "M_F_CPU0_SA_DQ<10>")
		)
		(pad "164" smd rect
			(at 2.050034 -47.174912 90)
			(size 0.519938 1.4986)
			(layers "F.Cu" "F.Mask" "F.Paste")
			(net "GND")
		)
		(pad "165" smd rect
			(at 2.050034 -46.325028 90)
			(size 0.519938 1.4986)
			(layers "F.Cu" "F.Mask" "F.Paste")
			(net "M_F_CPU0_SA_DQ<11>")
		)
		(pad "166" smd rect
			(at 2.050034 -45.47489 90)
			(size 0.519938 1.4986)
			(layers "F.Cu" "F.Mask" "F.Paste")
			(net "GND")
		)
		(pad "167" smd rect
			(at 2.050034 -44.625006 90)
			(size 0.519938 1.4986)
			(layers "F.Cu" "F.Mask" "F.Paste")
			(net "M_F_CPU0_SA_DQS_DN<6>")
		)
		(pad "168" smd rect
			(at 2.050034 -43.775122 90)
			(size 0.519938 1.4986)
			(layers "F.Cu" "F.Mask" "F.Paste")
			(net "M_F_CPU0_SA_DQS_DP<6>")
		)
		(pad "169" smd rect
			(at 2.050034 -42.924984 90)
			(size 0.519938 1.4986)
			(layers "F.Cu" "F.Mask" "F.Paste")
			(net "GND")
		)
		(pad "170" smd rect
			(at 2.050034 -42.0751 90)
			(size 0.519938 1.4986)
			(layers "F.Cu" "F.Mask" "F.Paste")
			(net "M_F_CPU0_SA_DQ<14>")
		)
		(pad "171" smd rect
			(at 2.050034 -41.224962 90)
			(size 0.519938 1.4986)
			(layers "F.Cu" "F.Mask" "F.Paste")
			(net "GND")
		)
		(pad "172" smd rect
			(at 2.050034 -40.375078 90)
			(size 0.519938 1.4986)
			(layers "F.Cu" "F.Mask" "F.Paste")
			(net "M_F_CPU0_SA_DQ<15>")
		)
		(pad "173" smd rect
			(at 2.050034 -39.52494 90)
			(size 0.519938 1.4986)
			(layers "F.Cu" "F.Mask" "F.Paste")
			(net "GND")
		)
		(pad "174" smd rect
			(at 2.050034 -38.675056 90)
			(size 0.519938 1.4986)
			(layers "F.Cu" "F.Mask" "F.Paste")
			(net "M_F_CPU0_SA_DQ<18>")
		)
		(pad "175" smd rect
			(at 2.050034 -37.824918 90)
			(size 0.519938 1.4986)
			(layers "F.Cu" "F.Mask" "F.Paste")
			(net "GND")
		)
		(pad "176" smd rect
			(at 2.050034 -36.975034 90)
			(size 0.519938 1.4986)
			(layers "F.Cu" "F.Mask" "F.Paste")
			(net "M_F_CPU0_SA_DQ<19>")
		)
		(pad "177" smd rect
			(at 2.050034 -36.124896 90)
			(size 0.519938 1.4986)
			(layers "F.Cu" "F.Mask" "F.Paste")
			(net "GND")
		)
		(pad "178" smd rect
			(at 2.050034 -35.275012 90)
			(size 0.519938 1.4986)
			(layers "F.Cu" "F.Mask" "F.Paste")
			(net "M_F_CPU0_SA_DQS_DN<7>")
		)
		(pad "179" smd rect
			(at 2.050034 -34.425128 90)
			(size 0.519938 1.4986)
			(layers "F.Cu" "F.Mask" "F.Paste")
			(net "M_F_CPU0_SA_DQS_DP<7>")
		)
		(pad "180" smd rect
			(at 2.050034 -33.57499 90)
			(size 0.519938 1.4986)
			(layers "F.Cu" "F.Mask" "F.Paste")
			(net "GND")
		)
		(pad "181" smd rect
			(at 2.050034 -32.725106 90)
			(size 0.519938 1.4986)
			(layers "F.Cu" "F.Mask" "F.Paste")
			(net "M_F_CPU0_SA_DQ<22>")
		)
		(pad "182" smd rect
			(at 2.050034 -31.874968 90)
			(size 0.519938 1.4986)
			(layers "F.Cu" "F.Mask" "F.Paste")
			(net "GND")
		)
		(pad "183" smd rect
			(at 2.050034 -31.025084 90)
			(size 0.519938 1.4986)
			(layers "F.Cu" "F.Mask" "F.Paste")
			(net "M_F_CPU0_SA_DQ<23>")
		)
		(pad "184" smd rect
			(at 2.050034 -30.174946 90)
			(size 0.519938 1.4986)
			(layers "F.Cu" "F.Mask" "F.Paste")
			(net "GND")
		)
	)
)
